FILE_TYPE = MULTI_PHYS_TABLE;
PART 'DIODEAC_DUAL_ARRAY'
{========================================================================================}
:VALUE         | PACK_TYPE | MATERIAL | PART_NUMBER    = ENVCOMP                  | PART_NUMBER  | JEDEC_TYPE       | DESCRIPTION                                       | CLASS | HEIGHT     | COMPONENT_TYPE | LEAD_LENGTH | LPID   | SPEED_URL                                                                                                                       | STATUS        | RPL   | AML | BUS_UNIT | DAYS  ;
{========================================================================================}
'ESD3V3U4ULC' | 'SM9'     | 'IC'     | 'G18435-001'(!) = 'YES;YES;YES;UNK;ok;VLD' | 'G18435-001' | 'LCC9_04_09_5MA' | '(USE SYM 7) IC,DS,DIO,SOP,ESDPROTECT,TVS'        | 'IC'  | '0.013 IN' | 'LCC'          | ''          | '2169' | 'http://speed.intel.com:8081/speed/module/pdm/item/pdm_item_detail_direct.asp?item_cde=G18435-001&item_rev=01&url_param=unused' | 'Conditional' | 'YES' | '2' | 'SMO_IC' | '???'
'ESD3V3U4ULC' | 'SM9'     | 'EMPTY'  | 'G18435-001'(!) = 'YES;YES;YES;UNK;ok;VLD' | 'G18435-001' | 'LCC9_04_09_5MA' | '(USE SYM 7) IC,DS,DIO,SOP,ESDPROTECT,TVS'        | 'IO'  | '0.013 IN' | 'LCC'          | ''          | '2169' | 'http://speed.intel.com:8081/speed/module/pdm/item/pdm_item_detail_direct.asp?item_cde=G18435-001&item_rev=01&url_param=unused' | 'Conditional' | 'YES' | '2' | 'SMO_IC' | '???'
END_PART
END.
